(kicad_pcb
	(version 20240108)
	(generator "pcbnew")
	(generator_version "8.0")
	(general
		(thickness 1.62)
		(legacy_teardrops no)
	)
	(paper "A4")
	(title_block
		(title "Jetson Orin Baseboard")
		(date "2025-03-12")
		(rev "1.3.4")
		(company "Antmicro Ltd")
		(comment 1 "www.antmicro.com")
		(comment 9 "footprints 40-42 of 677")
	)
	(layers
		(0 "F.Cu" signal)
		(1 "In1.Cu" signal)
		(2 "In2.Cu" signal)
		(3 "In3.Cu" signal)
		(4 "In4.Cu" jumper)
		(5 "In5.Cu" signal)
		(6 "In6.Cu" signal)
		(31 "B.Cu" signal)
		(32 "B.Adhes" user "B.Adhesive")
		(33 "F.Adhes" user "F.Adhesive")
		(34 "B.Paste" user)
		(35 "F.Paste" user)
		(36 "B.SilkS" user "B.Silkscreen")
		(37 "F.SilkS" user "F.Silkscreen")
		(38 "B.Mask" user)
		(39 "F.Mask" user)
		(40 "Dwgs.User" user "User.Drawings")
		(41 "Cmts.User" user "User.Comments")
		(42 "Eco1.User" user "User.Eco1")
		(43 "Eco2.User" user "User.Eco2")
		(44 "Edge.Cuts" user)
		(45 "Margin" user)
		(46 "B.CrtYd" user "B.Courtyard")
		(47 "F.CrtYd" user "F.Courtyard")
		(48 "B.Fab" user)
		(49 "F.Fab" user)
	)
	(footprint "antmicro-footprints:Spacer_Drill3.7mm_H6.5mm_9774065151R"
		(locked yes)
		(layer "F.Cu")
		(at 124.525 118.1125)
		(descr "Spacer M=3 h=6.5mm fi=5.1mm")
		(property "Reference" "H2"
			(at -1.95 -3.251 0)
			(layer "F.SilkS")
			(effects
				(font
					(size 0.7 0.7)
					(thickness 0.15)
				)
				(justify left bottom)
			)
		)
		(property "Value" "Spacer_Drill3.7mm_H6.5mm_9774065151R"
			(at 0 4 0)
			(layer "F.Fab")
			(effects
				(font
					(size 0.7 0.7)
					(thickness 0.15)
				)
				(justify left bottom)
			)
		)
		(property "Footprint" "antmicro-footprints:Spacer_Drill3.7mm_H6.5mm_9774065151R"
			(at 0 0 0)
			(layer "F.Fab")
			(hide yes)
			(effects
				(font
					(size 1.27 1.27)
					(thickness 0.15)
				)
			)
		)
		(property "Datasheet" "https://www.we-online.com/components/products/datasheet/9774065151R.pdf"
			(at 0 0 0)
			(layer "F.Fab")
			(hide yes)
			(effects
				(font
					(size 1.27 1.27)
					(thickness 0.15)
				)
			)
		)
		(property "Author" "Antmicro"
			(at 0 0 0)
			(layer "F.Fab")
			(hide yes)
			(effects
				(font
					(size 1 1)
					(thickness 0.15)
				)
			)
		)
		(property "License" "Apache-2.0"
			(at 0 0 0)
			(layer "F.Fab")
			(hide yes)
			(effects
				(font
					(size 1 1)
					(thickness 0.15)
				)
			)
		)
		(property "MPN" "9774065151R"
			(at 0 0 0)
			(layer "F.Fab")
			(hide yes)
			(effects
				(font
					(size 1 1)
					(thickness 0.15)
				)
			)
		)
		(property "Manufacturer" "Würth Elektronik"
			(at 0 0 0)
			(layer "F.Fab")
			(hide yes)
			(effects
				(font
					(size 1 1)
					(thickness 0.15)
				)
			)
		)
		(sheetname "SoM")
		(sheetfile "som.kicad_sch")
		(solder_paste_ratio -1)
		(attr smd)
		(fp_circle
			(center 0 0)
			(end 3.05 0)
			(stroke
				(width 0.05)
				(type solid)
			)
			(fill none)
			(layer "F.CrtYd")
		)
		(fp_circle
			(center 0 0)
			(end 2.6 0)
			(stroke
				(width 0.15)
				(type solid)
			)
			(fill none)
			(layer "F.Fab")
		)
		(fp_text user "Author: Antmicro"
			(at -3.05041 7.1 0)
			(layer "F.Fab")
			(hide yes)
			(effects
				(font
					(size 0.7 0.7)
					(thickness 0.15)
				)
				(justify left bottom)
			)
		)
		(fp_text user "${REFERENCE}"
			(at -3.05041 8.3 0)
			(layer "F.Fab")
			(hide yes)
			(effects
				(font
					(size 0.7 0.7)
					(thickness 0.15)
				)
				(justify left bottom)
			)
		)
		(fp_text user "License: Apache-2.0"
			(at -3.05041 5.9 0)
			(layer "F.Fab")
			(hide yes)
			(effects
				(font
					(size 0.7 0.7)
					(thickness 0.15)
				)
				(justify left bottom)
			)
		)
		(pad "" smd custom
			(at -1.7 -1.7)
			(size 0.62 0.62)
			(layers "F.Paste")
			(thermal_bridge_angle 90)
			(options
				(clearance outline)
				(anchor circle)
			)
			(primitives
				(gr_arc
					(start -0.250195 1.279127)
					(mid 0.285453 0.294389)
					(end 1.266786 -0.24747)
					(width 0.2)
				)
				(gr_arc
					(start -0.34334 1.279127)
					(mid 0.218448 0.232561)
					(end 1.259603 -0.339191)
					(width 0.2)
				)
				(gr_arc
					(start -0.436309 1.279127)
					(mid 0.152481 0.169693)
					(end 1.255279 -0.431435)
					(width 0.2)
				)
				(gr_arc
					(start -0.529126 1.279127)
					(mid 0.087542 0.105784)
					(end 1.253811 -0.524161)
					(width 0.2)
				)
				(gr_arc
					(start -0.621807 1.279127)
					(mid 0.0309 0.033527)
					(end 1.275473 -0.621136)
					(width 0.2)
				)
				(gr_arc
					(start -0.71437 1.279127)
					(mid -0.037758 -0.026651)
					(end 1.263664 -0.711602)
					(width 0.2)
				)
				(gr_arc
					(start -0.806826 1.279127)
					(mid -0.105837 -0.087395)
					(end 1.253435 -0.802342)
					(width 0.2)
				)
				(gr_arc
					(start -0.899187 1.279127)
					(mid -0.165236 -0.156885)
					(end 1.267475 -0.897258)
					(width 0.2)
				)
				(gr_arc
					(start -0.991463 1.279127)
					(mid -0.228522 -0.222449)
					(end 1.270645 -0.990112)
					(width 0.2)
				)
				(gr_arc
					(start -1.083663 1.279127)
					(mid -0.294507 -0.285313)
					(end 1.266278 -1.081674)
					(width 0.2)
				)
				(gr_line
					(start 1.279127 -0.250195)
					(end 1.279127 -1.083663)
					(width 0.2)
				)
				(gr_line
					(start -0.250195 1.279127)
					(end -1.083663 1.279127)
					(width 0.2)
				)
			)
		)
		(pad "" smd custom
			(at -1.7 1.7 90)
			(size 0.62 0.62)
			(layers "F.Paste")
			(thermal_bridge_angle 90)
			(options
				(clearance outline)
				(anchor circle)
			)
			(primitives
				(gr_arc
					(start -0.250195 1.279127)
					(mid 0.285453 0.294389)
					(end 1.266786 -0.24747)
					(width 0.2)
				)
				(gr_arc
					(start -0.34334 1.279127)
					(mid 0.218448 0.232561)
					(end 1.259603 -0.339191)
					(width 0.2)
				)
				(gr_arc
					(start -0.436309 1.279127)
					(mid 0.152481 0.169693)
					(end 1.255279 -0.431435)
					(width 0.2)
				)
				(gr_arc
					(start -0.529126 1.279127)
					(mid 0.087542 0.105784)
					(end 1.253811 -0.524161)
					(width 0.2)
				)
				(gr_arc
					(start -0.621807 1.279127)
					(mid 0.0309 0.033527)
					(end 1.275473 -0.621136)
					(width 0.2)
				)
				(gr_arc
					(start -0.71437 1.279127)
					(mid -0.037758 -0.026651)
					(end 1.263664 -0.711602)
					(width 0.2)
				)
				(gr_arc
					(start -0.806826 1.279127)
					(mid -0.105837 -0.087395)
					(end 1.253435 -0.802342)
					(width 0.2)
				)
				(gr_arc
					(start -0.899187 1.279127)
					(mid -0.165236 -0.156885)
					(end 1.267475 -0.897258)
					(width 0.2)
				)
				(gr_arc
					(start -0.991463 1.279127)
					(mid -0.228522 -0.222449)
					(end 1.270645 -0.990112)
					(width 0.2)
				)
				(gr_arc
					(start -1.083663 1.279127)
					(mid -0.294507 -0.285313)
					(end 1.266278 -1.081674)
					(width 0.2)
				)
				(gr_line
					(start 1.279127 -0.250195)
					(end 1.279127 -1.083663)
					(width 0.2)
				)
				(gr_line
					(start -0.250195 1.279127)
					(end -1.083663 1.279127)
					(width 0.2)
				)
			)
		)
		(pad "" smd custom
			(at 1.7 -1.7 270)
			(size 0.62 0.62)
			(layers "F.Paste")
			(thermal_bridge_angle 90)
			(options
				(clearance outline)
				(anchor circle)
			)
			(primitives
				(gr_arc
					(start -0.250195 1.279127)
					(mid 0.285453 0.294389)
					(end 1.266786 -0.24747)
					(width 0.2)
				)
				(gr_arc
					(start -0.34334 1.279127)
					(mid 0.218448 0.232561)
					(end 1.259603 -0.339191)
					(width 0.2)
				)
				(gr_arc
					(start -0.436309 1.279127)
					(mid 0.152481 0.169693)
					(end 1.255279 -0.431435)
					(width 0.2)
				)
				(gr_arc
					(start -0.529126 1.279127)
					(mid 0.087542 0.105784)
					(end 1.253811 -0.524161)
					(width 0.2)
				)
				(gr_arc
					(start -0.621807 1.279127)
					(mid 0.0309 0.033527)
					(end 1.275473 -0.621136)
					(width 0.2)
				)
				(gr_arc
					(start -0.71437 1.279127)
					(mid -0.037758 -0.026651)
					(end 1.263664 -0.711602)
					(width 0.2)
				)
				(gr_arc
					(start -0.806826 1.279127)
					(mid -0.105837 -0.087395)
					(end 1.253435 -0.802342)
					(width 0.2)
				)
				(gr_arc
					(start -0.899187 1.279127)
					(mid -0.165236 -0.156885)
					(end 1.267475 -0.897258)
					(width 0.2)
				)
				(gr_arc
					(start -0.991463 1.279127)
					(mid -0.228522 -0.222449)
					(end 1.270645 -0.990112)
					(width 0.2)
				)
				(gr_arc
					(start -1.083663 1.279127)
					(mid -0.294507 -0.285313)
					(end 1.266278 -1.081674)
					(width 0.2)
				)
				(gr_line
					(start 1.279127 -0.250195)
					(end 1.279127 -1.083663)
					(width 0.2)
				)
				(gr_line
					(start -0.250195 1.279127)
					(end -1.083663 1.279127)
					(width 0.2)
				)
			)
		)
		(pad "" smd custom
			(at 1.7 1.7 180)
			(size 0.62 0.62)
			(layers "F.Paste")
			(thermal_bridge_angle 90)
			(options
				(clearance outline)
				(anchor circle)
			)
			(primitives
				(gr_arc
					(start -0.250195 1.279127)
					(mid 0.285453 0.294389)
					(end 1.266786 -0.24747)
					(width 0.2)
				)
				(gr_arc
					(start -0.34334 1.279127)
					(mid 0.218448 0.232561)
					(end 1.259603 -0.339191)
					(width 0.2)
				)
				(gr_arc
					(start -0.436309 1.279127)
					(mid 0.152481 0.169693)
					(end 1.255279 -0.431435)
					(width 0.2)
				)
				(gr_arc
					(start -0.529126 1.279127)
					(mid 0.087542 0.105784)
					(end 1.253811 -0.524161)
					(width 0.2)
				)
				(gr_arc
					(start -0.621807 1.279127)
					(mid 0.0309 0.033527)
					(end 1.275473 -0.621136)
					(width 0.2)
				)
				(gr_arc
					(start -0.71437 1.279127)
					(mid -0.037758 -0.026651)
					(end 1.263664 -0.711602)
					(width 0.2)
				)
				(gr_arc
					(start -0.806826 1.279127)
					(mid -0.105837 -0.087395)
					(end 1.253435 -0.802342)
					(width 0.2)
				)
				(gr_arc
					(start -0.899187 1.279127)
					(mid -0.165236 -0.156885)
					(end 1.267475 -0.897258)
					(width 0.2)
				)
				(gr_arc
					(start -0.991463 1.279127)
					(mid -0.228522 -0.222449)
					(end 1.270645 -0.990112)
					(width 0.2)
				)
				(gr_arc
					(start -1.083663 1.279127)
					(mid -0.294507 -0.285313)
					(end 1.266278 -1.081674)
					(width 0.2)
				)
				(gr_line
					(start 1.279127 -0.250195)
					(end 1.279127 -1.083663)
					(width 0.2)
				)
				(gr_line
					(start -0.250195 1.279127)
					(end -1.083663 1.279127)
					(width 0.2)
				)
			)
		)
		(pad "1" thru_hole circle
			(at 0 0)
			(size 6 6)
			(drill 3.7)
			(layers "*.Cu" "*.Mask")
			(remove_unused_layers no)
			(net 1 "GND")
			(pintype "passive")
		)
	)
	(footprint "antmicro-footprints:Module_Jetson-Orin-NX-Nano"
		(layer "F.Cu")
		(at 92.742 98.588)
		(descr "Jetson Orin NX series and Jetson Orin Nano")
		(tags "Jetson Orin NX Nano")
		(property "Reference" "M1"
			(at 0 0 0)
			(layer "F.SilkS")
			(hide yes)
			(effects
				(font
					(size 0.7 0.7)
					(thickness 0.15)
				)
				(justify left bottom)
			)
		)
		(property "Value" "Jetson-Orin-NX-Nano"
			(at 0 1.2 0)
			(layer "F.Fab")
			(effects
				(font
					(size 0.7 0.7)
					(thickness 0.15)
				)
				(justify left bottom)
			)
		)
		(property "Footprint" "antmicro-footprints:Module_Jetson-Orin-NX-Nano"
			(at 0 0 0)
			(layer "F.Fab")
			(hide yes)
			(effects
				(font
					(size 1.27 1.27)
					(thickness 0.15)
				)
			)
		)
		(property "Datasheet" "https://static6.arrow.com/aropdfconversion/c4902ff7fe8bae4b5d563d5e41c1cfab77501490/jetson-orin-nx-datasheet-nvidia-us-web-2605318-5.pdf"
			(at 0 0 0)
			(layer "F.Fab")
			(hide yes)
			(effects
				(font
					(size 1.27 1.27)
					(thickness 0.15)
				)
			)
		)
		(property "Author" "Antmicro"
			(at 0 0 0)
			(layer "F.Fab")
			(hide yes)
			(effects
				(font
					(size 1 1)
					(thickness 0.15)
				)
			)
		)
		(property "Displayed name" "Jetson Orin NX Nano"
			(at 0 0 0)
			(layer "F.Fab")
			(hide yes)
			(effects
				(font
					(size 1 1)
					(thickness 0.15)
				)
			)
		)
		(property "License" "Apache-2.0"
			(at 0 0 0)
			(layer "F.Fab")
			(hide yes)
			(effects
				(font
					(size 1 1)
					(thickness 0.15)
				)
			)
		)
		(property "MPN" "900-13767-0000-000"
			(at 0 0 0)
			(layer "F.Fab")
			(hide yes)
			(effects
				(font
					(size 1 1)
					(thickness 0.15)
				)
			)
		)
		(property "Manufacturer" "Nvidia"
			(at 0 0 0)
			(layer "F.Fab")
			(hide yes)
			(effects
				(font
					(size 1 1)
					(thickness 0.15)
				)
			)
		)
		(sheetname "SoM")
		(sheetfile "som.kicad_sch")
		(attr exclude_from_pos_files exclude_from_bom dnp)
		(fp_text user "${REFERENCE}"
			(at -35.8 25.5 0)
			(layer "F.Fab")
			(hide yes)
			(effects
				(font
					(size 0.7 0.7)
					(thickness 0.15)
				)
				(justify left bottom)
			)
		)
		(fp_text user "Author: Antmicro"
			(at -35.8 26.7 0)
			(layer "F.Fab")
			(hide yes)
			(effects
				(font
					(size 0.7 0.7)
					(thickness 0.15)
				)
				(justify left bottom)
			)
		)
		(fp_text user "License: Apache-2.0"
			(at -35.8 27.9 0)
			(layer "F.Fab")
			(hide yes)
			(effects
				(font
					(size 0.7 0.7)
					(thickness 0.15)
				)
				(justify left bottom)
			)
		)
	)
	(footprint "antmicro-footprints:R_0402_1005Metric"
		(layer "F.Cu")
		(at 56.1 109.25 -90)
		(descr "Resistor SMD 0402")
		(tags "resistor SMD 0402")
		(property "Reference" "R250"
			(at 1.725 0.575 -90)
			(layer "F.SilkS")
			(effects
				(font
					(size 0.7 0.7)
					(thickness 0.15)
				)
				(justify left bottom)
			)
		)
		(property "Value" "R_10k_0402"
			(at 0 1.4 -90)
			(layer "F.Fab")
			(effects
				(font
					(size 0.7 0.7)
					(thickness 0.15)
				)
				(justify left bottom)
			)
		)
		(property "Footprint" "antmicro-footprints:R_0402_1005Metric"
			(at 0 0 -90)
			(layer "F.Fab")
			(hide yes)
			(effects
				(font
					(size 1.27 1.27)
					(thickness 0.15)
				)
			)
		)
		(property "Datasheet" "https://www.bourns.com/docs/product-datasheets/cr.pdf"
			(at 0 0 -90)
			(layer "F.Fab")
			(hide yes)
			(effects
				(font
					(size 1.27 1.27)
					(thickness 0.15)
				)
			)
		)
		(property "Author" "Antmicro"
			(at -53.15 165.35 0)
			(layer "F.Fab")
			(hide yes)
			(effects
				(font
					(size 1 1)
					(thickness 0.15)
				)
			)
		)
		(property "License" "Apache-2.0"
			(at -53.15 165.35 0)
			(layer "F.Fab")
			(hide yes)
			(effects
				(font
					(size 1 1)
					(thickness 0.15)
				)
			)
		)
		(property "MPN" "CR0402-FX-1002GLF"
			(at -53.15 165.35 0)
			(layer "F.Fab")
			(hide yes)
			(effects
				(font
					(size 1 1)
					(thickness 0.15)
				)
			)
		)
		(property "Manufacturer" "Bourns"
			(at -53.15 165.35 0)
			(layer "F.Fab")
			(hide yes)
			(effects
				(font
					(size 1 1)
					(thickness 0.15)
				)
			)
		)
		(property "Tolerance" "1%"
			(at -53.15 165.35 0)
			(layer "F.Fab")
			(hide yes)
			(effects
				(font
					(size 1 1)
					(thickness 0.15)
				)
			)
		)
		(property "Val" "10k"
			(at -53.15 165.35 0)
			(layer "F.Fab")
			(hide yes)
			(effects
				(font
					(size 1 1)
					(thickness 0.15)
				)
			)
		)
		(sheetname "Supply")
		(sheetfile "supply.kicad_sch")
		(attr smd)
		(fp_rect
			(start -0.925 -0.47)
			(end 0.925 0.47)
			(stroke
				(width 0.05)
				(type default)
			)
			(fill none)
			(layer "F.CrtYd")
		)
		(fp_rect
			(start -0.5 -0.25)
			(end 0.5 0.25)
			(stroke
				(width 0.15)
				(type solid)
			)
			(fill none)
			(layer "F.Fab")
		)
		(fp_text user "Author: Antmicro"
			(at -0.95 4.169 -90)
			(layer "F.Fab")
			(hide yes)
			(effects
				(font
					(size 0.7 0.7)
					(thickness 0.15)
				)
				(justify left bottom)
			)
		)
		(fp_text user "${REFERENCE}"
			(at -0.95 3.168 -90)
			(layer "F.Fab")
			(hide yes)
			(effects
				(font
					(size 0.7 0.7)
					(thickness 0.15)
				)
				(justify left bottom)
			)
		)
		(fp_text user "License: Apache-2.0"
			(at -0.95 5.169 -90)
			(layer "F.Fab")
			(hide yes)
			(effects
				(font
					(size 0.7 0.7)
					(thickness 0.15)
				)
				(justify left bottom)
			)
		)
		(pad "1" smd roundrect
			(at -0.48 0 270)
			(size 0.59 0.64)
			(layers "F.Cu" "F.Paste" "F.Mask")
			(roundrect_rratio 0.25)
			(net 1 "GND")
			(pintype "passive")
		)
		(pad "2" smd roundrect
			(at 0.48 0 270)
			(size 0.59 0.64)
			(layers "F.Cu" "F.Paste" "F.Mask")
			(roundrect_rratio 0.25)
			(net 717 "Net-(Q13-Pad2)")
			(pintype "passive")
		)
	)
)
